(kicad_pcb
	(version 20260206)
	(generator "pcbnew")
	(generator_version "10.0")
	(general
		(thickness 1.6)
		(legacy_teardrops no)
	)
	(paper "A4")
	(title_block
		(title "04192023_DAF0TMB3IC0_F0TG_MB_C_brd_V02_OCP.brd")
		(comment 1 "Grand Teton / footprints 1717-1723 of 8354")
	)
	(layers
		(0 "F.Cu" signal "TOP")
		(4 "In1.Cu" signal "GND")
		(6 "In2.Cu" signal "IN1")
		(8 "In3.Cu" signal "GND1")
		(10 "In4.Cu" signal "IN2")
		(12 "In5.Cu" signal "GND2")
		(14 "In6.Cu" signal "IN3")
		(16 "In7.Cu" signal "GND3")
		(18 "In8.Cu" signal "VCC")
		(20 "In9.Cu" signal "VCC1")
		(22 "In10.Cu" signal "GND4")
		(24 "In11.Cu" signal "IN4")
		(26 "In12.Cu" signal "GND5")
		(28 "In13.Cu" signal "IN5")
		(30 "In14.Cu" signal "GND6")
		(32 "In15.Cu" signal "IN6")
		(34 "In16.Cu" signal "GND7")
		(2 "B.Cu" signal "BOTTOM")
		(9 "F.Adhes" user "F.Adhesive")
		(11 "B.Adhes" user "B.Adhesive")
		(13 "F.Paste" user "Package Geometry/Pastemask Top")
		(15 "B.Paste" user "Package Geometry/Pastemask Bottom")
		(5 "F.SilkS" user "Ref Des/Silkscreen Top")
		(7 "B.SilkS" user "Ref Des/Silkscreen Bottom")
		(1 "F.Mask" user "Board Geometry/Soldermask Top")
		(3 "B.Mask" user "Board Geometry/Soldermask Bottom")
		(17 "Dwgs.User" user "User.Drawings")
		(19 "Cmts.User" user "User.Comments")
		(21 "Eco1.User" user "User.Eco1")
		(23 "Eco2.User" user "User.Eco2")
		(25 "Edge.Cuts" user "Board Geometry/Outline")
		(27 "Margin" user)
		(31 "F.CrtYd" user "Package Geometry/Place Bound Top")
		(29 "B.CrtYd" user "Package Geometry/Place Bound Bottom")
		(35 "F.Fab" user "Ref Des/Assembly Top")
		(33 "B.Fab" user "Ref Des/Assembly Bottom")
	)
	(footprint ""
		(layer "F.Cu")
		(at 118.511574 -148.291042 -90)
		(property "Reference" "PL37"
			(at -0.575056 -3.974084 90)
			(unlocked yes)
			(layer "F.SilkS")
			(effects
				(font
					(size 0.7874 0.5842)
					(thickness 0.1524)
				)
				(justify left)
			)
		)
		(property "Value" ""
			(at 0 0 270)
			(layer "F.Fab")
			(effects
				(font
					(size 1.27 1.27)
				)
			)
		)
		(duplicate_pad_numbers_are_jumpers no)
		(fp_line
			(start -3.050032 2.999994)
			(end 3.050032 2.999994)
			(stroke
				(width 0.1524)
				(type default)
			)
			(layer "F.SilkS")
		)
		(fp_line
			(start 3.050032 2.999994)
			(end 3.050032 1.4478)
			(stroke
				(width 0.1524)
				(type default)
			)
			(layer "F.SilkS")
		)
		(fp_line
			(start -3.050032 1.4478)
			(end -3.050032 2.999994)
			(stroke
				(width 0.1524)
				(type default)
			)
			(layer "F.SilkS")
		)
		(fp_line
			(start 3.050032 -1.4478)
			(end 3.050032 -2.999994)
			(stroke
				(width 0.1524)
				(type default)
			)
			(layer "F.SilkS")
		)
		(fp_line
			(start -3.050032 -2.999994)
			(end -3.050032 -1.4478)
			(stroke
				(width 0.1524)
				(type default)
			)
			(layer "F.SilkS")
		)
		(fp_line
			(start 3.050032 -2.999994)
			(end -3.050032 -2.999994)
			(stroke
				(width 0.1524)
				(type default)
			)
			(layer "F.SilkS")
		)
		(fp_line
			(start -3.050032 2.999994)
			(end 3.050032 2.999994)
			(stroke
				(width 0.1)
				(type default)
			)
			(layer "F.Fab")
		)
		(fp_line
			(start 3.050032 2.999994)
			(end 3.050032 -2.999994)
			(stroke
				(width 0.1)
				(type default)
			)
			(layer "F.Fab")
		)
		(fp_line
			(start -3.050032 -2.999994)
			(end -3.050032 2.999994)
			(stroke
				(width 0.1)
				(type default)
			)
			(layer "F.Fab")
		)
		(fp_line
			(start 3.050032 -2.999994)
			(end -3.050032 -2.999994)
			(stroke
				(width 0.1)
				(type default)
			)
			(layer "F.Fab")
		)
		(pad "1" smd rect
			(at -2.525014 0 270)
			(size 1.651 2.6162)
			(layers "F.Cu" "F.Mask" "F.Paste")
			(net "SW_P12V_AUX_PVDDCR_SOC_P1_FLT")
		)
		(pad "2" smd rect
			(at 2.525014 0 270)
			(size 1.651 2.6162)
			(layers "F.Cu" "F.Mask" "F.Paste")
			(net "P12V_AUX")
		)
	)
	(footprint ""
		(layer "F.Cu")
		(at 339.70722 -335.022698 -90)
		(property "Reference" "PC133_C1P0_5"
			(at 0 0 270)
			(layer "F.SilkS")
			(hide yes)
			(effects
				(font
					(size 1.27 1.27)
				)
			)
		)
		(property "Value" ""
			(at 0 0 270)
			(layer "F.Fab")
			(effects
				(font
					(size 1.27 1.27)
				)
			)
		)
		(duplicate_pad_numbers_are_jumpers no)
		(fp_line
			(start -0.7874 0.4064)
			(end -0.7874 -0.4064)
			(stroke
				(width 0.1524)
				(type default)
			)
			(layer "F.SilkS")
		)
		(fp_line
			(start 0.7874 0.4064)
			(end -0.7874 0.4064)
			(stroke
				(width 0.1524)
				(type default)
			)
			(layer "F.SilkS")
		)
		(fp_line
			(start -0.7874 -0.4064)
			(end 0.7874 -0.4064)
			(stroke
				(width 0.1524)
				(type default)
			)
			(layer "F.SilkS")
		)
		(fp_line
			(start 0.7874 -0.4064)
			(end 0.7874 0.4064)
			(stroke
				(width 0.1524)
				(type default)
			)
			(layer "F.SilkS")
		)
		(fp_line
			(start -0.67945 0.3048)
			(end -0.67945 -0.305054)
			(stroke
				(width 0.1)
				(type default)
			)
			(layer "F.Fab")
		)
		(fp_line
			(start -0.12065 0.3048)
			(end -0.67945 0.3048)
			(stroke
				(width 0.1)
				(type default)
			)
			(layer "F.Fab")
		)
		(fp_line
			(start 0.120396 0.3048)
			(end 0.120396 0.2794)
			(stroke
				(width 0.1)
				(type default)
			)
			(layer "F.Fab")
		)
		(fp_line
			(start 0.67945 0.3048)
			(end 0.120396 0.3048)
			(stroke
				(width 0.1)
				(type default)
			)
			(layer "F.Fab")
		)
		(fp_line
			(start -0.12065 0.2794)
			(end -0.12065 0.3048)
			(stroke
				(width 0.1)
				(type default)
			)
			(layer "F.Fab")
		)
		(fp_line
			(start 0.120396 0.2794)
			(end -0.12065 0.2794)
			(stroke
				(width 0.1)
				(type default)
			)
			(layer "F.Fab")
		)
		(fp_line
			(start -0.12065 -0.2794)
			(end 0.12065 -0.2794)
			(stroke
				(width 0.1)
				(type default)
			)
			(layer "F.Fab")
		)
		(fp_line
			(start 0.12065 -0.2794)
			(end 0.12065 -0.3048)
			(stroke
				(width 0.1)
				(type default)
			)
			(layer "F.Fab")
		)
		(fp_line
			(start 0.12065 -0.3048)
			(end 0.67945 -0.3048)
			(stroke
				(width 0.1)
				(type default)
			)
			(layer "F.Fab")
		)
		(fp_line
			(start 0.67945 -0.3048)
			(end 0.67945 0.3048)
			(stroke
				(width 0.1)
				(type default)
			)
			(layer "F.Fab")
		)
		(fp_line
			(start -0.67945 -0.305054)
			(end -0.12065 -0.305054)
			(stroke
				(width 0.1)
				(type default)
			)
			(layer "F.Fab")
		)
		(fp_line
			(start -0.12065 -0.305054)
			(end -0.12065 -0.2794)
			(stroke
				(width 0.1)
				(type default)
			)
			(layer "F.Fab")
		)
		(pad "1" smd circle
			(at -0.40005 0 270)
			(size 0 0)
			(layers "F.Cu" "F.Mask" "F.Paste")
			(net "PVDDCR_CPU1_P0_PVCC")
		)
		(pad "2" smd circle
			(at 0.40005 0 270)
			(size 0 0)
			(layers "F.Cu" "F.Mask" "F.Paste")
			(net "GND")
		)
	)
	(footprint ""
		(layer "F.Cu")
		(at 240.792 -283.5148 180)
		(property "Reference" "PC6503"
			(at 0 0 180)
			(layer "F.SilkS")
			(hide yes)
			(effects
				(font
					(size 1.27 1.27)
				)
			)
		)
		(property "Value" ""
			(at 0 0 180)
			(layer "F.Fab")
			(effects
				(font
					(size 1.27 1.27)
				)
			)
		)
		(duplicate_pad_numbers_are_jumpers no)
		(fp_line
			(start 1.524 0.762)
			(end -1.524 0.762)
			(stroke
				(width 0.1524)
				(type default)
			)
			(layer "F.SilkS")
		)
		(fp_line
			(start 1.524 -0.762)
			(end 1.524 0.762)
			(stroke
				(width 0.1524)
				(type default)
			)
			(layer "F.SilkS")
		)
		(fp_line
			(start -1.524 0.762)
			(end -1.524 -0.762)
			(stroke
				(width 0.1524)
				(type default)
			)
			(layer "F.SilkS")
		)
		(fp_line
			(start -1.524 -0.762)
			(end 1.524 -0.762)
			(stroke
				(width 0.1524)
				(type default)
			)
			(layer "F.SilkS")
		)
		(fp_line
			(start 1.1049 0.724916)
			(end 1.1049 -0.724916)
			(stroke
				(width 0.1)
				(type default)
			)
			(layer "F.Fab")
		)
		(fp_line
			(start 1.1049 -0.724916)
			(end -1.1049 -0.724916)
			(stroke
				(width 0.1)
				(type default)
			)
			(layer "F.Fab")
		)
		(fp_line
			(start -1.1049 0.724916)
			(end 1.1049 0.724916)
			(stroke
				(width 0.1)
				(type default)
			)
			(layer "F.Fab")
		)
		(fp_line
			(start -1.1049 -0.724916)
			(end -1.1049 0.724916)
			(stroke
				(width 0.1)
				(type default)
			)
			(layer "F.Fab")
		)
		(pad "1" smd rect
			(at -0.889 0)
			(size 1.016 1.27)
			(layers "F.Cu" "F.Mask" "F.Paste")
			(net "SW_P12V_AUX_P1V8_RETIMER_CPU0_FLT")
		)
		(pad "2" smd rect
			(at 0.889 0)
			(size 1.016 1.27)
			(layers "F.Cu" "F.Mask" "F.Paste")
			(net "GND")
		)
	)
	(footprint ""
		(layer "F.Cu")
		(at 191.41694 -403.611842)
		(property "Reference" "PR3937"
			(at 0 0 0)
			(layer "F.SilkS")
			(hide yes)
			(effects
				(font
					(size 1.27 1.27)
				)
			)
		)
		(property "Value" ""
			(at 0 0 0)
			(layer "F.Fab")
			(effects
				(font
					(size 1.27 1.27)
				)
			)
		)
		(duplicate_pad_numbers_are_jumpers no)
		(fp_line
			(start -0.7874 -0.4064)
			(end 0.7874 -0.4064)
			(stroke
				(width 0.1524)
				(type default)
			)
			(layer "F.SilkS")
		)
		(fp_line
			(start -0.7874 0.4064)
			(end -0.7874 -0.4064)
			(stroke
				(width 0.1524)
				(type default)
			)
			(layer "F.SilkS")
		)
		(fp_line
			(start 0.7874 -0.4064)
			(end 0.7874 0.4064)
			(stroke
				(width 0.1524)
				(type default)
			)
			(layer "F.SilkS")
		)
		(fp_line
			(start 0.7874 0.4064)
			(end -0.7874 0.4064)
			(stroke
				(width 0.1524)
				(type default)
			)
			(layer "F.SilkS")
		)
		(fp_line
			(start -0.67945 -0.305054)
			(end -0.12065 -0.305054)
			(stroke
				(width 0.1)
				(type default)
			)
			(layer "F.Fab")
		)
		(fp_line
			(start -0.67945 0.3048)
			(end -0.67945 -0.305054)
			(stroke
				(width 0.1)
				(type default)
			)
			(layer "F.Fab")
		)
		(fp_line
			(start -0.12065 -0.305054)
			(end -0.12065 -0.2794)
			(stroke
				(width 0.1)
				(type default)
			)
			(layer "F.Fab")
		)
		(fp_line
			(start -0.12065 -0.2794)
			(end 0.12065 -0.2794)
			(stroke
				(width 0.1)
				(type default)
			)
			(layer "F.Fab")
		)
		(fp_line
			(start -0.12065 0.2794)
			(end -0.12065 0.3048)
			(stroke
				(width 0.1)
				(type default)
			)
			(layer "F.Fab")
		)
		(fp_line
			(start -0.12065 0.3048)
			(end -0.67945 0.3048)
			(stroke
				(width 0.1)
				(type default)
			)
			(layer "F.Fab")
		)
		(fp_line
			(start 0.120396 0.2794)
			(end -0.12065 0.2794)
			(stroke
				(width 0.1)
				(type default)
			)
			(layer "F.Fab")
		)
		(fp_line
			(start 0.120396 0.3048)
			(end 0.120396 0.2794)
			(stroke
				(width 0.1)
				(type default)
			)
			(layer "F.Fab")
		)
		(fp_line
			(start 0.12065 -0.3048)
			(end 0.67945 -0.3048)
			(stroke
				(width 0.1)
				(type default)
			)
			(layer "F.Fab")
		)
		(fp_line
			(start 0.12065 -0.2794)
			(end 0.12065 -0.3048)
			(stroke
				(width 0.1)
				(type default)
			)
			(layer "F.Fab")
		)
		(fp_line
			(start 0.67945 -0.3048)
			(end 0.67945 0.3048)
			(stroke
				(width 0.1)
				(type default)
			)
			(layer "F.Fab")
		)
		(fp_line
			(start 0.67945 0.3048)
			(end 0.120396 0.3048)
			(stroke
				(width 0.1)
				(type default)
			)
			(layer "F.Fab")
		)
		(pad "1" smd circle
			(at -0.40005 0)
			(size 0 0)
			(layers "F.Cu" "F.Mask" "F.Paste")
			(net "HSC_MODE")
		)
		(pad "2" smd circle
			(at 0.40005 0)
			(size 0 0)
			(layers "F.Cu" "F.Mask" "F.Paste")
			(net "AGND_HSC")
		)
	)
	(footprint ""
		(layer "F.Cu")
		(at 299.72 -108.966 -90)
		(property "Reference" "R1345"
			(at 0 0 270)
			(layer "F.SilkS")
			(hide yes)
			(effects
				(font
					(size 1.27 1.27)
				)
			)
		)
		(property "Value" ""
			(at 0 0 270)
			(layer "F.Fab")
			(effects
				(font
					(size 1.27 1.27)
				)
			)
		)
		(duplicate_pad_numbers_are_jumpers no)
		(fp_line
			(start -0.7874 0.4064)
			(end -0.7874 -0.4064)
			(stroke
				(width 0.1524)
				(type default)
			)
			(layer "F.SilkS")
		)
		(fp_line
			(start 0.7874 0.4064)
			(end -0.7874 0.4064)
			(stroke
				(width 0.1524)
				(type default)
			)
			(layer "F.SilkS")
		)
		(fp_line
			(start -0.7874 -0.4064)
			(end 0.7874 -0.4064)
			(stroke
				(width 0.1524)
				(type default)
			)
			(layer "F.SilkS")
		)
		(fp_line
			(start 0.7874 -0.4064)
			(end 0.7874 0.4064)
			(stroke
				(width 0.1524)
				(type default)
			)
			(layer "F.SilkS")
		)
		(fp_line
			(start -0.67945 0.3048)
			(end -0.67945 -0.305054)
			(stroke
				(width 0.1)
				(type default)
			)
			(layer "F.Fab")
		)
		(fp_line
			(start -0.12065 0.3048)
			(end -0.67945 0.3048)
			(stroke
				(width 0.1)
				(type default)
			)
			(layer "F.Fab")
		)
		(fp_line
			(start 0.120396 0.3048)
			(end 0.120396 0.2794)
			(stroke
				(width 0.1)
				(type default)
			)
			(layer "F.Fab")
		)
		(fp_line
			(start 0.67945 0.3048)
			(end 0.120396 0.3048)
			(stroke
				(width 0.1)
				(type default)
			)
			(layer "F.Fab")
		)
		(fp_line
			(start -0.12065 0.2794)
			(end -0.12065 0.3048)
			(stroke
				(width 0.1)
				(type default)
			)
			(layer "F.Fab")
		)
		(fp_line
			(start 0.120396 0.2794)
			(end -0.12065 0.2794)
			(stroke
				(width 0.1)
				(type default)
			)
			(layer "F.Fab")
		)
		(fp_line
			(start -0.12065 -0.2794)
			(end 0.12065 -0.2794)
			(stroke
				(width 0.1)
				(type default)
			)
			(layer "F.Fab")
		)
		(fp_line
			(start 0.12065 -0.2794)
			(end 0.12065 -0.3048)
			(stroke
				(width 0.1)
				(type default)
			)
			(layer "F.Fab")
		)
		(fp_line
			(start 0.12065 -0.3048)
			(end 0.67945 -0.3048)
			(stroke
				(width 0.1)
				(type default)
			)
			(layer "F.Fab")
		)
		(fp_line
			(start 0.67945 -0.3048)
			(end 0.67945 0.3048)
			(stroke
				(width 0.1)
				(type default)
			)
			(layer "F.Fab")
		)
		(fp_line
			(start -0.67945 -0.305054)
			(end -0.12065 -0.305054)
			(stroke
				(width 0.1)
				(type default)
			)
			(layer "F.Fab")
		)
		(fp_line
			(start -0.12065 -0.305054)
			(end -0.12065 -0.2794)
			(stroke
				(width 0.1)
				(type default)
			)
			(layer "F.Fab")
		)
		(pad "1" smd circle
			(at -0.40005 0 270)
			(size 0 0)
			(layers "F.Cu" "F.Mask" "F.Paste")
			(net "SMB_INA230_3V3AUX_SDA")
		)
		(pad "2" smd circle
			(at 0.40005 0 270)
			(size 0 0)
			(layers "F.Cu" "F.Mask" "F.Paste")
			(net "SMB_INA230_6_3V3AUX_SDA_R")
		)
	)
	(footprint ""
		(layer "F.Cu")
		(at 167.132 -120.360948 180)
		(property "Reference" "R639"
			(at 0 0 180)
			(layer "F.SilkS")
			(hide yes)
			(effects
				(font
					(size 1.27 1.27)
				)
			)
		)
		(property "Value" ""
			(at 0 0 180)
			(layer "F.Fab")
			(effects
				(font
					(size 1.27 1.27)
				)
			)
		)
		(duplicate_pad_numbers_are_jumpers no)
		(fp_line
			(start 0.7874 0.4064)
			(end -0.7874 0.4064)
			(stroke
				(width 0.1524)
				(type default)
			)
			(layer "F.SilkS")
		)
		(fp_line
			(start 0.7874 -0.4064)
			(end 0.7874 0.4064)
			(stroke
				(width 0.1524)
				(type default)
			)
			(layer "F.SilkS")
		)
		(fp_line
			(start -0.7874 0.4064)
			(end -0.7874 -0.4064)
			(stroke
				(width 0.1524)
				(type default)
			)
			(layer "F.SilkS")
		)
		(fp_line
			(start -0.7874 -0.4064)
			(end 0.7874 -0.4064)
			(stroke
				(width 0.1524)
				(type default)
			)
			(layer "F.SilkS")
		)
		(fp_line
			(start 0.67945 0.3048)
			(end 0.120396 0.3048)
			(stroke
				(width 0.1)
				(type default)
			)
			(layer "F.Fab")
		)
		(fp_line
			(start 0.67945 -0.3048)
			(end 0.67945 0.3048)
			(stroke
				(width 0.1)
				(type default)
			)
			(layer "F.Fab")
		)
		(fp_line
			(start 0.12065 -0.2794)
			(end 0.12065 -0.3048)
			(stroke
				(width 0.1)
				(type default)
			)
			(layer "F.Fab")
		)
		(fp_line
			(start 0.12065 -0.3048)
			(end 0.67945 -0.3048)
			(stroke
				(width 0.1)
				(type default)
			)
			(layer "F.Fab")
		)
		(fp_line
			(start 0.120396 0.3048)
			(end 0.120396 0.2794)
			(stroke
				(width 0.1)
				(type default)
			)
			(layer "F.Fab")
		)
		(fp_line
			(start 0.120396 0.2794)
			(end -0.12065 0.2794)
			(stroke
				(width 0.1)
				(type default)
			)
			(layer "F.Fab")
		)
		(fp_line
			(start -0.12065 0.3048)
			(end -0.67945 0.3048)
			(stroke
				(width 0.1)
				(type default)
			)
			(layer "F.Fab")
		)
		(fp_line
			(start -0.12065 0.2794)
			(end -0.12065 0.3048)
			(stroke
				(width 0.1)
				(type default)
			)
			(layer "F.Fab")
		)
		(fp_line
			(start -0.12065 -0.2794)
			(end 0.12065 -0.2794)
			(stroke
				(width 0.1)
				(type default)
			)
			(layer "F.Fab")
		)
		(fp_line
			(start -0.12065 -0.305054)
			(end -0.12065 -0.2794)
			(stroke
				(width 0.1)
				(type default)
			)
			(layer "F.Fab")
		)
		(fp_line
			(start -0.67945 0.3048)
			(end -0.67945 -0.305054)
			(stroke
				(width 0.1)
				(type default)
			)
			(layer "F.Fab")
		)
		(fp_line
			(start -0.67945 -0.305054)
			(end -0.12065 -0.305054)
			(stroke
				(width 0.1)
				(type default)
			)
			(layer "F.Fab")
		)
		(pad "1" smd circle
			(at -0.40005 0 180)
			(size 0 0)
			(layers "F.Cu" "F.Mask" "F.Paste")
			(net "CPLD_PROGRAMN")
		)
		(pad "2" smd circle
			(at 0.40005 0 180)
			(size 0 0)
			(layers "F.Cu" "F.Mask" "F.Paste")
			(net "P3V3_AUX")
		)
	)
	(footprint ""
		(layer "F.Cu")
		(at 7.124192 -99.42195)
		(property "Reference" "Y8004"
			(at -2.821178 -3.284728 0)
			(unlocked yes)
			(layer "F.SilkS")
			(effects
				(font
					(size 0.7874 0.5842)
					(thickness 0.1524)
				)
				(justify left)
			)
		)
		(property "Value" ""
			(at 0 0 0)
			(layer "F.Fab")
			(effects
				(font
					(size 1.27 1.27)
				)
			)
		)
		(duplicate_pad_numbers_are_jumpers no)
		(fp_line
			(start -1.380236 -1.579372)
			(end -1.380236 1.579372)
			(stroke
				(width 0.1524)
				(type default)
			)
			(layer "F.SilkS")
		)
		(fp_line
			(start -1.380236 1.579372)
			(end 1.380236 1.579372)
			(stroke
				(width 0.1524)
				(type default)
			)
			(layer "F.SilkS")
		)
		(fp_line
			(start 1.380236 -1.579372)
			(end -1.380236 -1.579372)
			(stroke
				(width 0.1524)
				(type default)
			)
			(layer "F.SilkS")
		)
		(fp_line
			(start 1.380236 1.579372)
			(end 1.380236 -1.579372)
			(stroke
				(width 0.1524)
				(type default)
			)
			(layer "F.SilkS")
		)
		(fp_poly
			(pts
				(xy -2.914396 -1.099312) (xy -2.914396 -0.337312) (xy -2.152396 -0.718312)
			)
			(stroke
				(width 0)
				(type default)
			)
			(fill yes)
			(layer "F.SilkS")
		)
		(fp_line
			(start -1.050036 -1.299972)
			(end -1.050036 1.299972)
			(stroke
				(width 0.1)
				(type default)
			)
			(layer "F.Fab")
		)
		(fp_line
			(start -1.050036 1.299972)
			(end 1.050036 1.299972)
			(stroke
				(width 0.1)
				(type default)
			)
			(layer "F.Fab")
		)
		(fp_line
			(start 1.050036 -1.299972)
			(end -1.050036 -1.299972)
			(stroke
				(width 0.1)
				(type default)
			)
			(layer "F.Fab")
		)
		(fp_line
			(start 1.050036 1.299972)
			(end 1.050036 -1.299972)
			(stroke
				(width 0.1)
				(type default)
			)
			(layer "F.Fab")
		)
		(fp_poly
			(pts
				(xy -2.3114 -1.306068) (xy -2.3114 -0.544068) (xy -1.5494 -0.925068)
			)
			(stroke
				(width 0)
				(type default)
			)
			(fill yes)
			(layer "F.Fab")
		)
		(pad "1" smd rect
			(at -0.774954 -0.925068)
			(size 0.9144 1.016)
			(layers "F.Cu" "F.Mask" "F.Paste")
			(net "USB_HUB_XTAL_IN")
		)
		(pad "2" smd rect
			(at -0.774954 0.925068)
			(size 0.9144 1.016)
			(layers "F.Cu" "F.Mask" "F.Paste")
			(net "GND")
		)
		(pad "3" smd rect
			(at 0.774954 0.925068)
			(size 0.9144 1.016)
			(layers "F.Cu" "F.Mask" "F.Paste")
			(net "USB_HUB_XTAL_OUT")
		)
		(pad "4" smd rect
			(at 0.774954 -0.925068)
			(size 0.9144 1.016)
			(layers "F.Cu" "F.Mask" "F.Paste")
			(net "GND")
		)
	)
)
